# T6G (Grand Teton) — schematic netlist excerpt (pin names and nets, part order shuffled) for the footprints in the layout excerpt that follows; sources: Cadence DE-HDL packaged netlist, KiCad conversion of 04192023_DAF0TMB3IC0_F0TG_MB_C_brd_V02_OCP.brd

U149  SN74AVC4T774PWR  IC  pkg TSSOP16XC  page 172
  DIR1  = PVDD18_S5_P0
  DIR2  = PVDD18_S5_P0
  A1  = HDT_HDR_TCK
  A2  = HDT_HDR_TMS
  A3  = HDT_HDR_TRST_N
  A4  = HDT_HDR_DBREQ_N
  DIR3  = PVDD18_S5_P0
  DIR4  = PVDD18_S5_P0
  OE  = JTAG_BMC_R_D_OE
  GND  = GND
  B4  = JTAG_DBREQ_R_N
  B3  = JTAG_TRST_R_N
  B2  = JTAG_TMS_R
  B1  = JTAG_TCK_R
  VCCB  = PVDD18_S5_P0
  VCCA  = PVDD18_S5_P0

PC185  Q_CAP  560PF 50V 10% EMPTY  pkg C0402  page 198 : A = SW_PVDDCR_SOC_P0_SW1 ; B = SW_PVDDCR_SOC_P0_SW1_RC

(kicad_pcb
	(version 20260206)
	(generator "pcbnew")
	(generator_version "10.0")
	(general
		(thickness 1.6)
		(legacy_teardrops no)
	)
	(paper "A4")
	(title_block
		(title "04192023_DAF0TMB3IC0_F0TG_MB_C_brd_V02_OCP.brd")
		(comment 1 "Grand Teton / footprints 4670-4671 of 8354")
	)
	(layers
		(0 "F.Cu" signal "TOP")
		(4 "In1.Cu" signal "GND")
		(6 "In2.Cu" signal "IN1")
		(8 "In3.Cu" signal "GND1")
		(10 "In4.Cu" signal "IN2")
		(12 "In5.Cu" signal "GND2")
		(14 "In6.Cu" signal "IN3")
		(16 "In7.Cu" signal "GND3")
		(18 "In8.Cu" signal "VCC")
		(20 "In9.Cu" signal "VCC1")
		(22 "In10.Cu" signal "GND4")
		(24 "In11.Cu" signal "IN4")
		(26 "In12.Cu" signal "GND5")
		(28 "In13.Cu" signal "IN5")
		(30 "In14.Cu" signal "GND6")
		(32 "In15.Cu" signal "IN6")
		(34 "In16.Cu" signal "GND7")
		(2 "B.Cu" signal "BOTTOM")
		(9 "F.Adhes" user "F.Adhesive")
		(11 "B.Adhes" user "B.Adhesive")
		(13 "F.Paste" user "Package Geometry/Pastemask Top")
		(15 "B.Paste" user "Package Geometry/Pastemask Bottom")
		(5 "F.SilkS" user "Ref Des/Silkscreen Top")
		(7 "B.SilkS" user "Ref Des/Silkscreen Bottom")
		(1 "F.Mask" user "Board Geometry/Soldermask Top")
		(3 "B.Mask" user "Board Geometry/Soldermask Bottom")
		(17 "Dwgs.User" user "User.Drawings")
		(19 "Cmts.User" user "User.Comments")
		(21 "Eco1.User" user "User.Eco1")
		(23 "Eco2.User" user "User.Eco2")
		(25 "Edge.Cuts" user "Board Geometry/Outline")
		(27 "Margin" user)
		(31 "F.CrtYd" user "Package Geometry/Place Bound Top")
		(29 "B.CrtYd" user "Package Geometry/Place Bound Bottom")
		(35 "F.Fab" user "Ref Des/Assembly Top")
		(33 "B.Fab" user "Ref Des/Assembly Bottom")
	)
	(footprint ""
		(layer "F.Cu")
		(at 266.971526 -97.780856 180)
		(property "Reference" "U149"
			(at 1.889252 -3.344164 0)
			(unlocked yes)
			(layer "F.SilkS")
			(effects
				(font
					(size 0.7874 0.5842)
					(thickness 0.1524)
				)
				(justify left)
			)
		)
		(property "Value" ""
			(at 0 0 180)
			(layer "F.Fab")
			(effects
				(font
					(size 1.27 1.27)
				)
			)
		)
		(duplicate_pad_numbers_are_jumpers no)
		(fp_line
			(start 1.868932 2.549906)
			(end 1.868932 -2.549906)
			(stroke
				(width 0.1524)
				(type default)
			)
			(layer "F.SilkS")
		)
		(fp_line
			(start 1.868932 -2.549906)
			(end 1.025906 -2.549906)
			(stroke
				(width 0.1524)
				(type default)
			)
			(layer "F.SilkS")
		)
		(fp_line
			(start 1.025906 -2.549906)
			(end 0 -1.524)
			(stroke
				(width 0.1524)
				(type default)
			)
			(layer "F.SilkS")
		)
		(fp_line
			(start 0 -1.524)
			(end -1.025906 -2.549906)
			(stroke
				(width 0.1524)
				(type default)
			)
			(layer "F.SilkS")
		)
		(fp_line
			(start -1.025906 -2.549906)
			(end -1.868932 -2.549906)
			(stroke
				(width 0.1524)
				(type default)
			)
			(layer "F.SilkS")
		)
		(fp_line
			(start -1.868932 2.549906)
			(end 1.868932 2.549906)
			(stroke
				(width 0.1524)
				(type default)
			)
			(layer "F.SilkS")
		)
		(fp_line
			(start -1.868932 -2.549906)
			(end -1.868932 2.549906)
			(stroke
				(width 0.1524)
				(type default)
			)
			(layer "F.SilkS")
		)
		(fp_poly
			(pts
				(xy -3.7592 -2.295398) (xy -4.7752 -1.787398) (xy -4.7752 -2.803398)
			)
			(stroke
				(width 0)
				(type default)
			)
			(fill yes)
			(layer "F.SilkS")
		)
		(fp_line
			(start 2.249932 2.549906)
			(end 2.249932 -2.549906)
			(stroke
				(width 0.1)
				(type default)
			)
			(layer "F.Fab")
		)
		(fp_line
			(start 2.249932 -2.549906)
			(end -2.249932 -2.549906)
			(stroke
				(width 0.1)
				(type default)
			)
			(layer "F.Fab")
		)
		(fp_line
			(start -2.249932 2.549906)
			(end 2.249932 2.549906)
			(stroke
				(width 0.1)
				(type default)
			)
			(layer "F.Fab")
		)
		(fp_line
			(start -2.249932 -2.549906)
			(end -2.249932 2.549906)
			(stroke
				(width 0.1)
				(type default)
			)
			(layer "F.Fab")
		)
		(fp_poly
			(pts
				(xy -4.7752 -1.787398) (xy -4.7752 -2.803398) (xy -3.7592 -2.295398)
			)
			(stroke
				(width 0)
				(type default)
			)
			(fill yes)
			(layer "F.Fab")
		)
		(pad "1" smd rect
			(at -2.800096 -2.275078 90)
			(size 0.3556 1.6002)
			(layers "F.Cu" "F.Mask" "F.Paste")
			(net "PVDD18_S5_P0")
		)
		(pad "2" smd rect
			(at -2.800096 -1.625092 90)
			(size 0.3556 1.6002)
			(layers "F.Cu" "F.Mask" "F.Paste")
			(net "PVDD18_S5_P0")
		)
		(pad "3" smd rect
			(at -2.800096 -0.975106 90)
			(size 0.3556 1.6002)
			(layers "F.Cu" "F.Mask" "F.Paste")
			(net "HDT_HDR_TCK")
		)
		(pad "4" smd rect
			(at -2.800096 -0.32512 90)
			(size 0.3556 1.6002)
			(layers "F.Cu" "F.Mask" "F.Paste")
			(net "HDT_HDR_TMS")
		)
		(pad "5" smd rect
			(at -2.800096 0.32512 90)
			(size 0.3556 1.6002)
			(layers "F.Cu" "F.Mask" "F.Paste")
			(net "HDT_HDR_TRST_N")
		)
		(pad "6" smd rect
			(at -2.800096 0.975106 90)
			(size 0.3556 1.6002)
			(layers "F.Cu" "F.Mask" "F.Paste")
			(net "HDT_HDR_DBREQ_N")
		)
		(pad "7" smd rect
			(at -2.800096 1.625092 90)
			(size 0.3556 1.6002)
			(layers "F.Cu" "F.Mask" "F.Paste")
			(net "PVDD18_S5_P0")
		)
		(pad "8" smd rect
			(at -2.800096 2.275078 90)
			(size 0.3556 1.6002)
			(layers "F.Cu" "F.Mask" "F.Paste")
			(net "PVDD18_S5_P0")
		)
		(pad "9" smd rect
			(at 2.800096 2.275078 90)
			(size 0.3556 1.6002)
			(layers "F.Cu" "F.Mask" "F.Paste")
			(net "JTAG_BMC_R_D_OE")
		)
		(pad "10" smd rect
			(at 2.800096 1.625092 90)
			(size 0.3556 1.6002)
			(layers "F.Cu" "F.Mask" "F.Paste")
			(net "GND")
		)
		(pad "11" smd rect
			(at 2.800096 0.975106 90)
			(size 0.3556 1.6002)
			(layers "F.Cu" "F.Mask" "F.Paste")
			(net "JTAG_DBREQ_R_N")
		)
		(pad "12" smd rect
			(at 2.800096 0.32512 90)
			(size 0.3556 1.6002)
			(layers "F.Cu" "F.Mask" "F.Paste")
			(net "JTAG_TRST_R_N")
		)
		(pad "13" smd rect
			(at 2.800096 -0.32512 90)
			(size 0.3556 1.6002)
			(layers "F.Cu" "F.Mask" "F.Paste")
			(net "JTAG_TMS_R")
		)
		(pad "14" smd rect
			(at 2.800096 -0.975106 90)
			(size 0.3556 1.6002)
			(layers "F.Cu" "F.Mask" "F.Paste")
			(net "JTAG_TCK_R")
		)
		(pad "15" smd rect
			(at 2.800096 -1.625092 90)
			(size 0.3556 1.6002)
			(layers "F.Cu" "F.Mask" "F.Paste")
			(net "PVDD18_S5_P0")
		)
		(pad "16" smd rect
			(at 2.800096 -2.275078 90)
			(size 0.3556 1.6002)
			(layers "F.Cu" "F.Mask" "F.Paste")
			(net "PVDD18_S5_P0")
		)
	)
	(footprint ""
		(layer "F.Cu")
		(at 401.51812 -180.175408)
		(property "Reference" "PC185"
			(at 0 0 0)
			(layer "F.SilkS")
			(hide yes)
			(effects
				(font
					(size 1.27 1.27)
				)
			)
		)
		(property "Value" ""
			(at 0 0 0)
			(layer "F.Fab")
			(effects
				(font
					(size 1.27 1.27)
				)
			)
		)
		(duplicate_pad_numbers_are_jumpers no)
		(fp_line
			(start -0.7874 -0.4064)
			(end 0.7874 -0.4064)
			(stroke
				(width 0.1524)
				(type default)
			)
			(layer "F.SilkS")
		)
		(fp_line
			(start -0.7874 0.4064)
			(end -0.7874 -0.4064)
			(stroke
				(width 0.1524)
				(type default)
			)
			(layer "F.SilkS")
		)
		(fp_line
			(start 0.7874 -0.4064)
			(end 0.7874 0.4064)
			(stroke
				(width 0.1524)
				(type default)
			)
			(layer "F.SilkS")
		)
		(fp_line
			(start 0.7874 0.4064)
			(end -0.7874 0.4064)
			(stroke
				(width 0.1524)
				(type default)
			)
			(layer "F.SilkS")
		)
		(fp_line
			(start -0.67945 -0.305054)
			(end -0.12065 -0.305054)
			(stroke
				(width 0.1)
				(type default)
			)
			(layer "F.Fab")
		)
		(fp_line
			(start -0.67945 0.3048)
			(end -0.67945 -0.305054)
			(stroke
				(width 0.1)
				(type default)
			)
			(layer "F.Fab")
		)
		(fp_line
			(start -0.12065 -0.305054)
			(end -0.12065 -0.2794)
			(stroke
				(width 0.1)
				(type default)
			)
			(layer "F.Fab")
		)
		(fp_line
			(start -0.12065 -0.2794)
			(end 0.12065 -0.2794)
			(stroke
				(width 0.1)
				(type default)
			)
			(layer "F.Fab")
		)
		(fp_line
			(start -0.12065 0.2794)
			(end -0.12065 0.3048)
			(stroke
				(width 0.1)
				(type default)
			)
			(layer "F.Fab")
		)
		(fp_line
			(start -0.12065 0.3048)
			(end -0.67945 0.3048)
			(stroke
				(width 0.1)
				(type default)
			)
			(layer "F.Fab")
		)
		(fp_line
			(start 0.120396 0.2794)
			(end -0.12065 0.2794)
			(stroke
				(width 0.1)
				(type default)
			)
			(layer "F.Fab")
		)
		(fp_line
			(start 0.120396 0.3048)
			(end 0.120396 0.2794)
			(stroke
				(width 0.1)
				(type default)
			)
			(layer "F.Fab")
		)
		(fp_line
			(start 0.12065 -0.3048)
			(end 0.67945 -0.3048)
			(stroke
				(width 0.1)
				(type default)
			)
			(layer "F.Fab")
		)
		(fp_line
			(start 0.12065 -0.2794)
			(end 0.12065 -0.3048)
			(stroke
				(width 0.1)
				(type default)
			)
			(layer "F.Fab")
		)
		(fp_line
			(start 0.67945 -0.3048)
			(end 0.67945 0.3048)
			(stroke
				(width 0.1)
				(type default)
			)
			(layer "F.Fab")
		)
		(fp_line
			(start 0.67945 0.3048)
			(end 0.120396 0.3048)
			(stroke
				(width 0.1)
				(type default)
			)
			(layer "F.Fab")
		)
		(pad "1" smd circle
			(at -0.40005 0)
			(size 0 0)
			(layers "F.Cu" "F.Mask" "F.Paste")
			(net "SW_PVDDCR_SOC_P0_SW1")
		)
		(pad "2" smd circle
			(at 0.40005 0)
			(size 0 0)
			(layers "F.Cu" "F.Mask" "F.Paste")
			(net "SW_PVDDCR_SOC_P0_SW1_RC")
		)
	)
)
